(kicad_sch
	(version 20231120)
	(generator "eeschema")
	(generator_version "8.0")
	(paper "A3" portrait)
	(title_block
		(title "Thunderbolt GPU Adapter")
		(date "2024-07-09")
		(rev "1.3.0")
		(company "Antmicro Ltd")
		(comment 1 "www.antmicro.com")
	)
	(symbol
		(lib_id "antmicroFiducialMarks:Fiducial_1mm_Mask3mm")
		(at 47.625 389.89 0)
		(unit 1)
		(exclude_from_sim no)
		(in_bom no)
		(on_board yes)
		(dnp no)
		(fields_autoplaced yes)
		(property "Reference" "FID4"
			(at 52.07 388.6199 0)
			(effects
				(font
					(size 1.27 1.27)
				)
				(justify left)
			)
		)
		(property "Value" "Fiducial_1mm_Mask3mm"
			(at 52.07 391.1599 0)
			(effects
				(font
					(size 1.27 1.27)
				)
				(justify left)
			)
		)
		(property "Footprint" "antmicro-footprints:Fiducial_1mm_Mask3mm"
			(at 47.625 389.89 0)
			(effects
				(font
					(size 1.27 1.27)
				)
				(hide yes)
			)
		)
		(property "Datasheet" ""
			(at 47.625 389.89 0)
			(effects
				(font
					(size 1.27 1.27)
				)
				(hide yes)
			)
		)
		(property "Description" ""
			(at 47.625 389.89 0)
			(effects
				(font
					(size 1.27 1.27)
				)
				(hide yes)
			)
		)
		(property "Author" "Antmicro"
			(at 65.405 407.67 0)
			(effects
				(font
					(size 1.27 1.27)
					(thickness 0.15)
				)
				(justify left bottom)
				(hide yes)
			)
		)
		(property "License" "Apache-2.0"
			(at 65.405 410.21 0)
			(effects
				(font
					(size 1.27 1.27)
					(thickness 0.15)
				)
				(justify left bottom)
				(hide yes)
			)
		)
		(instances
			(project "thunderbolt-gpu-adapter"
				(path ""
					(reference "FID4")
					(unit 1)
				)
			)
		)
	)
	(symbol
		(lib_id "antmicroFiducialMarks:Fiducial_1mm_Mask3mm")
		(at 47.625 375.92 0)
		(unit 1)
		(exclude_from_sim no)
		(in_bom no)
		(on_board yes)
		(dnp no)
		(fields_autoplaced yes)
		(property "Reference" "FID2"
			(at 52.07 374.6499 0)
			(effects
				(font
					(size 1.27 1.27)
				)
				(justify left)
			)
		)
		(property "Value" "Fiducial_1mm_Mask3mm"
			(at 52.07 377.1899 0)
			(effects
				(font
					(size 1.27 1.27)
				)
				(justify left)
			)
		)
		(property "Footprint" "antmicro-footprints:Fiducial_1mm_Mask3mm"
			(at 47.625 375.92 0)
			(effects
				(font
					(size 1.27 1.27)
				)
				(hide yes)
			)
		)
		(property "Datasheet" ""
			(at 47.625 375.92 0)
			(effects
				(font
					(size 1.27 1.27)
				)
				(hide yes)
			)
		)
		(property "Description" ""
			(at 47.625 375.92 0)
			(effects
				(font
					(size 1.27 1.27)
				)
				(hide yes)
			)
		)
		(property "Author" "Antmicro"
			(at 65.405 393.7 0)
			(effects
				(font
					(size 1.27 1.27)
					(thickness 0.15)
				)
				(justify left bottom)
				(hide yes)
			)
		)
		(property "License" "Apache-2.0"
			(at 65.405 396.24 0)
			(effects
				(font
					(size 1.27 1.27)
					(thickness 0.15)
				)
				(justify left bottom)
				(hide yes)
			)
		)
		(instances
			(project "thunderbolt-gpu-adapter"
				(path ""
					(reference "FID2")
					(unit 1)
				)
			)
		)
	)
	(symbol
		(lib_id "antmicroMechanicalParts:antmicro_logo")
		(at 124.46 391.16 0)
		(unit 1)
		(exclude_from_sim no)
		(in_bom no)
		(on_board yes)
		(dnp no)
		(fields_autoplaced yes)
		(property "Reference" "N1"
			(at 130.81 389.1762 0)
			(effects
				(font
					(size 1.27 1.27)
					(thickness 0.15)
				)
				(justify left)
			)
		)
		(property "Value" "antmicro_logo"
			(at 130.81 391.7162 0)
			(effects
				(font
					(size 1.27 1.27)
					(thickness 0.15)
				)
				(justify left)
			)
		)
		(property "Footprint" "antmicro-footprints:antmicro-logo"
			(at 139.7 401.32 0)
			(effects
				(font
					(size 1.27 1.27)
					(thickness 0.15)
				)
				(justify left bottom)
				(hide yes)
			)
		)
		(property "Datasheet" ""
			(at 139.7 403.86 0)
			(effects
				(font
					(size 1.27 1.27)
					(thickness 0.15)
				)
				(justify left bottom)
				(hide yes)
			)
		)
		(property "Description" ""
			(at 124.46 391.16 0)
			(effects
				(font
					(size 1.27 1.27)
				)
				(hide yes)
			)
		)
		(property "MPN" ""
			(at 124.46 391.16 0)
			(effects
				(font
					(size 1.27 1.27)
				)
			)
		)
		(property "Manufacturer" ""
			(at 139.7 411.48 0)
			(effects
				(font
					(size 1.27 1.27)
					(thickness 0.15)
				)
				(justify left bottom)
				(hide yes)
			)
		)
		(property "Author" "Antmicro"
			(at 139.7 406.4 0)
			(effects
				(font
					(size 1.27 1.27)
					(thickness 0.15)
				)
				(justify left bottom)
				(hide yes)
			)
		)
		(property "License" "Apache-2.0"
			(at 139.7 408.94 0)
			(effects
				(font
					(size 1.27 1.27)
					(thickness 0.15)
				)
				(justify left bottom)
				(hide yes)
			)
		)
		(instances
			(project "thunderbolt-gpu-adapter"
				(path ""
					(reference "N1")
					(unit 1)
				)
			)
		)
	)
	(symbol
		(lib_id "antmicroFiducialMarks:Fiducial_1mm_Mask3mm")
		(at 89.535 382.905 0)
		(unit 1)
		(exclude_from_sim no)
		(in_bom no)
		(on_board yes)
		(dnp no)
		(fields_autoplaced yes)
		(property "Reference" "FID7"
			(at 93.98 381.6349 0)
			(effects
				(font
					(size 1.27 1.27)
				)
				(justify left)
			)
		)
		(property "Value" "Fiducial_1mm_Mask3mm"
			(at 93.98 384.1749 0)
			(effects
				(font
					(size 1.27 1.27)
				)
				(justify left)
			)
		)
		(property "Footprint" "antmicro-footprints:Fiducial_1mm_Mask3mm"
			(at 89.535 382.905 0)
			(effects
				(font
					(size 1.27 1.27)
				)
				(hide yes)
			)
		)
		(property "Datasheet" ""
			(at 89.535 382.905 0)
			(effects
				(font
					(size 1.27 1.27)
				)
				(hide yes)
			)
		)
		(property "Description" ""
			(at 89.535 382.905 0)
			(effects
				(font
					(size 1.27 1.27)
				)
				(hide yes)
			)
		)
		(property "Author" "Antmicro"
			(at 107.315 400.685 0)
			(effects
				(font
					(size 1.27 1.27)
					(thickness 0.15)
				)
				(justify left bottom)
				(hide yes)
			)
		)
		(property "License" "Apache-2.0"
			(at 107.315 403.225 0)
			(effects
				(font
					(size 1.27 1.27)
					(thickness 0.15)
				)
				(justify left bottom)
				(hide yes)
			)
		)
		(instances
			(project "thunderbolt-gpu-adapter"
				(path ""
					(reference "FID7")
					(unit 1)
				)
			)
		)
	)
	(symbol
		(lib_id "antmicroFiducialMarks:Fiducial_1mm_Mask3mm")
		(at 89.535 389.89 0)
		(unit 1)
		(exclude_from_sim no)
		(in_bom no)
		(on_board yes)
		(dnp no)
		(fields_autoplaced yes)
		(property "Reference" "FID8"
			(at 93.98 388.6199 0)
			(effects
				(font
					(size 1.27 1.27)
				)
				(justify left)
			)
		)
		(property "Value" "Fiducial_1mm_Mask3mm"
			(at 93.98 391.1599 0)
			(effects
				(font
					(size 1.27 1.27)
				)
				(justify left)
			)
		)
		(property "Footprint" "antmicro-footprints:Fiducial_1mm_Mask3mm"
			(at 89.535 389.89 0)
			(effects
				(font
					(size 1.27 1.27)
				)
				(hide yes)
			)
		)
		(property "Datasheet" ""
			(at 89.535 389.89 0)
			(effects
				(font
					(size 1.27 1.27)
				)
				(hide yes)
			)
		)
		(property "Description" ""
			(at 89.535 389.89 0)
			(effects
				(font
					(size 1.27 1.27)
				)
				(hide yes)
			)
		)
		(property "Author" "Antmicro"
			(at 107.315 407.67 0)
			(effects
				(font
					(size 1.27 1.27)
					(thickness 0.15)
				)
				(justify left bottom)
				(hide yes)
			)
		)
		(property "License" "Apache-2.0"
			(at 107.315 410.21 0)
			(effects
				(font
					(size 1.27 1.27)
					(thickness 0.15)
				)
				(justify left bottom)
				(hide yes)
			)
		)
		(instances
			(project "thunderbolt-gpu-adapter"
				(path ""
					(reference "FID8")
					(unit 1)
				)
			)
		)
	)
	(symbol
		(lib_id "antmicroFiducialMarks:Fiducial_1mm_Mask3mm")
		(at 47.625 382.905 0)
		(unit 1)
		(exclude_from_sim no)
		(in_bom no)
		(on_board yes)
		(dnp no)
		(fields_autoplaced yes)
		(property "Reference" "FID3"
			(at 52.07 381.6349 0)
			(effects
				(font
					(size 1.27 1.27)
				)
				(justify left)
			)
		)
		(property "Value" "Fiducial_1mm_Mask3mm"
			(at 52.07 384.1749 0)
			(effects
				(font
					(size 1.27 1.27)
				)
				(justify left)
			)
		)
		(property "Footprint" "antmicro-footprints:Fiducial_1mm_Mask3mm"
			(at 47.625 382.905 0)
			(effects
				(font
					(size 1.27 1.27)
				)
				(hide yes)
			)
		)
		(property "Datasheet" ""
			(at 47.625 382.905 0)
			(effects
				(font
					(size 1.27 1.27)
				)
				(hide yes)
			)
		)
		(property "Description" ""
			(at 47.625 382.905 0)
			(effects
				(font
					(size 1.27 1.27)
				)
				(hide yes)
			)
		)
		(property "Author" "Antmicro"
			(at 65.405 400.685 0)
			(effects
				(font
					(size 1.27 1.27)
					(thickness 0.15)
				)
				(justify left bottom)
				(hide yes)
			)
		)
		(property "License" "Apache-2.0"
			(at 65.405 403.225 0)
			(effects
				(font
					(size 1.27 1.27)
					(thickness 0.15)
				)
				(justify left bottom)
				(hide yes)
			)
		)
		(instances
			(project "thunderbolt-gpu-adapter"
				(path ""
					(reference "FID3")
					(unit 1)
				)
			)
		)
	)
	(symbol
		(lib_id "antmicroFiducialMarks:Fiducial_1mm_Mask3mm")
		(at 47.625 368.935 0)
		(unit 1)
		(exclude_from_sim no)
		(in_bom no)
		(on_board yes)
		(dnp no)
		(fields_autoplaced yes)
		(property "Reference" "FID1"
			(at 52.07 367.6649 0)
			(effects
				(font
					(size 1.27 1.27)
				)
				(justify left)
			)
		)
		(property "Value" "Fiducial_1mm_Mask3mm"
			(at 52.07 370.2049 0)
			(effects
				(font
					(size 1.27 1.27)
				)
				(justify left)
			)
		)
		(property "Footprint" "antmicro-footprints:Fiducial_1mm_Mask3mm"
			(at 47.625 368.935 0)
			(effects
				(font
					(size 1.27 1.27)
				)
				(hide yes)
			)
		)
		(property "Datasheet" ""
			(at 47.625 368.935 0)
			(effects
				(font
					(size 1.27 1.27)
				)
				(hide yes)
			)
		)
		(property "Description" ""
			(at 47.625 368.935 0)
			(effects
				(font
					(size 1.27 1.27)
				)
				(hide yes)
			)
		)
		(property "Author" "Antmicro"
			(at 65.405 386.715 0)
			(effects
				(font
					(size 1.27 1.27)
					(thickness 0.15)
				)
				(justify left bottom)
				(hide yes)
			)
		)
		(property "License" "Apache-2.0"
			(at 65.405 389.255 0)
			(effects
				(font
					(size 1.27 1.27)
					(thickness 0.15)
				)
				(justify left bottom)
				(hide yes)
			)
		)
		(instances
			(project "thunderbolt-gpu-adapter"
				(path ""
					(reference "FID1")
					(unit 1)
				)
			)
		)
	)
	(symbol
		(lib_id "antmicroFiducialMarks:Fiducial_1mm_Mask3mm")
		(at 89.535 375.92 0)
		(unit 1)
		(exclude_from_sim no)
		(in_bom no)
		(on_board yes)
		(dnp no)
		(fields_autoplaced yes)
		(property "Reference" "FID6"
			(at 93.98 374.6499 0)
			(effects
				(font
					(size 1.27 1.27)
				)
				(justify left)
			)
		)
		(property "Value" "Fiducial_1mm_Mask3mm"
			(at 93.98 377.1899 0)
			(effects
				(font
					(size 1.27 1.27)
				)
				(justify left)
			)
		)
		(property "Footprint" "antmicro-footprints:Fiducial_1mm_Mask3mm"
			(at 89.535 375.92 0)
			(effects
				(font
					(size 1.27 1.27)
				)
				(hide yes)
			)
		)
		(property "Datasheet" ""
			(at 89.535 375.92 0)
			(effects
				(font
					(size 1.27 1.27)
				)
				(hide yes)
			)
		)
		(property "Description" ""
			(at 89.535 375.92 0)
			(effects
				(font
					(size 1.27 1.27)
				)
				(hide yes)
			)
		)
		(property "Author" "Antmicro"
			(at 107.315 393.7 0)
			(effects
				(font
					(size 1.27 1.27)
					(thickness 0.15)
				)
				(justify left bottom)
				(hide yes)
			)
		)
		(property "License" "Apache-2.0"
			(at 107.315 396.24 0)
			(effects
				(font
					(size 1.27 1.27)
					(thickness 0.15)
				)
				(justify left bottom)
				(hide yes)
			)
		)
		(instances
			(project "thunderbolt-gpu-adapter"
				(path ""
					(reference "FID6")
					(unit 1)
				)
			)
		)
	)
	(symbol
		(lib_id "antmicroFiducialMarks:Fiducial_1mm_Mask3mm")
		(at 89.535 368.935 0)
		(unit 1)
		(exclude_from_sim no)
		(in_bom no)
		(on_board yes)
		(dnp no)
		(fields_autoplaced yes)
		(property "Reference" "FID5"
			(at 93.98 367.6649 0)
			(effects
				(font
					(size 1.27 1.27)
				)
				(justify left)
			)
		)
		(property "Value" "Fiducial_1mm_Mask3mm"
			(at 93.98 370.2049 0)
			(effects
				(font
					(size 1.27 1.27)
				)
				(justify left)
			)
		)
		(property "Footprint" "antmicro-footprints:Fiducial_1mm_Mask3mm"
			(at 89.535 368.935 0)
			(effects
				(font
					(size 1.27 1.27)
				)
				(hide yes)
			)
		)
		(property "Datasheet" ""
			(at 89.535 368.935 0)
			(effects
				(font
					(size 1.27 1.27)
				)
				(hide yes)
			)
		)
		(property "Description" ""
			(at 89.535 368.935 0)
			(effects
				(font
					(size 1.27 1.27)
				)
				(hide yes)
			)
		)
		(property "Author" "Antmicro"
			(at 107.315 386.715 0)
			(effects
				(font
					(size 1.27 1.27)
					(thickness 0.15)
				)
				(justify left bottom)
				(hide yes)
			)
		)
		(property "License" "Apache-2.0"
			(at 107.315 389.255 0)
			(effects
				(font
					(size 1.27 1.27)
					(thickness 0.15)
				)
				(justify left bottom)
				(hide yes)
			)
		)
		(instances
			(project "thunderbolt-gpu-adapter"
				(path ""
					(reference "FID5")
					(unit 1)
				)
			)
		)
	)
	(sheet
		(at 50.8 190.5)
		(size 77.47 64.77)
		(fields_autoplaced yes)
		(stroke
			(width 0.1524)
			(type solid)
		)
		(fill
			(color 0 0 0 0.0000)
		)
		(property "Sheetname" "Connectors"
			(at 50.8 189.7884 0)
			(effects
				(font
					(size 1.27 1.27)
				)
				(justify left bottom)
			)
		)
		(property "Sheetfile" "connectors.kicad_sch"
			(at 50.8 255.8546 0)
			(effects
				(font
					(size 1.27 1.27)
				)
				(justify left top)
			)
		)
		(instances
			(project "thunderbolt-gpu-adapter"
				(path ""
					(page "2")
				)
			)
		)
	)
	(sheet
		(at 171.45 273.05)
		(size 77.47 64.77)
		(fields_autoplaced yes)
		(stroke
			(width 0.1524)
			(type solid)
		)
		(fill
			(color 0 0 0 0.0000)
		)
		(property "Sheetname" "TB Controller"
			(at 171.45 272.3384 0)
			(effects
				(font
					(size 1.27 1.27)
				)
				(justify left bottom)
			)
		)
		(property "Sheetfile" "tb.kicad_sch"
			(at 171.45 338.4046 0)
			(effects
				(font
					(size 1.27 1.27)
				)
				(justify left top)
			)
		)
		(instances
			(project "thunderbolt-gpu-adapter"
				(path ""
					(page "5")
				)
			)
		)
	)
	(sheet
		(at 171.45 190.5)
		(size 77.47 64.77)
		(fields_autoplaced yes)
		(stroke
			(width 0.1524)
			(type solid)
		)
		(fill
			(color 0 0 0 0.0000)
		)
		(property "Sheetname" "Power"
			(at 171.45 189.7884 0)
			(effects
				(font
					(size 1.27 1.27)
				)
				(justify left bottom)
			)
		)
		(property "Sheetfile" "power.kicad_sch"
			(at 171.45 255.8546 0)
			(effects
				(font
					(size 1.27 1.27)
				)
				(justify left top)
			)
		)
		(instances
			(project "thunderbolt-gpu-adapter"
				(path ""
					(page "3")
				)
			)
		)
	)
	(sheet
		(at 50.8 273.05)
		(size 77.47 64.77)
		(fields_autoplaced yes)
		(stroke
			(width 0.1524)
			(type solid)
		)
		(fill
			(color 0 0 0 0.0000)
		)
		(property "Sheetname" "Thunderbolt Controller - Power"
			(at 50.8 272.3384 0)
			(effects
				(font
					(size 1.27 1.27)
				)
				(justify left bottom)
			)
		)
		(property "Sheetfile" "tb-power.kicad_sch"
			(at 50.8 338.4046 0)
			(effects
				(font
					(size 1.27 1.27)
				)
				(justify left top)
			)
		)
		(instances
			(project "thunderbolt-gpu-adapter"
				(path ""
					(page "4")
				)
			)
		)
	)
	(sheet_instances
		(path "/"
			(page "1")
		)
	)
)
